(kicad_pcb
	(version 20260206)
	(generator "pcbnew")
	(generator_version "10.0")
	(general
		(thickness 1.6)
		(legacy_teardrops no)
	)
	(paper "A4")
	(title_block
		(title "03242023_DA0F0TMBIJ0_F0T_Motherboard_J_brd_V01_OCP.brd")
		(comment 1 "Grand Teton / footprints 2571-2576 of 6105")
	)
	(layers
		(0 "F.Cu" signal "TOP")
		(4 "In1.Cu" signal "GND")
		(6 "In2.Cu" signal "IN1")
		(8 "In3.Cu" signal "GND1")
		(10 "In4.Cu" signal "IN2")
		(12 "In5.Cu" signal "GND2")
		(14 "In6.Cu" signal "IN3")
		(16 "In7.Cu" signal "GND3")
		(18 "In8.Cu" signal "VCC")
		(20 "In9.Cu" signal "VCC1")
		(22 "In10.Cu" signal "GND4")
		(24 "In11.Cu" signal "IN4")
		(26 "In12.Cu" signal "GND5")
		(28 "In13.Cu" signal "IN5")
		(30 "In14.Cu" signal "GND6")
		(32 "In15.Cu" signal "IN6")
		(34 "In16.Cu" signal "GND7")
		(2 "B.Cu" signal "BOTTOM")
		(9 "F.Adhes" user "F.Adhesive")
		(11 "B.Adhes" user "B.Adhesive")
		(13 "F.Paste" user "Package Geometry/Pastemask Top")
		(15 "B.Paste" user "Package Geometry/Pastemask Bottom")
		(5 "F.SilkS" user "Ref Des/Silkscreen Top")
		(7 "B.SilkS" user "Ref Des/Silkscreen Bottom")
		(1 "F.Mask" user "Board Geometry/Soldermask Top")
		(3 "B.Mask" user "Board Geometry/Soldermask Bottom")
		(17 "Dwgs.User" user "User.Drawings")
		(19 "Cmts.User" user "User.Comments")
		(21 "Eco1.User" user "User.Eco1")
		(23 "Eco2.User" user "User.Eco2")
		(25 "Edge.Cuts" user "Board Geometry/Outline")
		(27 "Margin" user)
		(31 "F.CrtYd" user "Package Geometry/Place Bound Top")
		(29 "B.CrtYd" user "Package Geometry/Place Bound Bottom")
		(35 "F.Fab" user "Ref Des/Assembly Top")
		(33 "B.Fab" user "Ref Des/Assembly Bottom")
	)
	(footprint ""
		(layer "F.Cu")
		(at 31.856426 -70.83425 180)
		(property "Reference" "R3147"
			(at 0 0 180)
			(layer "F.SilkS")
			(hide yes)
			(effects
				(font
					(size 1.27 1.27)
				)
			)
		)
		(property "Value" ""
			(at 0 0 180)
			(layer "F.Fab")
			(effects
				(font
					(size 1.27 1.27)
				)
			)
		)
		(duplicate_pad_numbers_are_jumpers no)
		(fp_line
			(start 0.7874 0.4064)
			(end -0.7874 0.4064)
			(stroke
				(width 0.1524)
				(type default)
			)
			(layer "F.SilkS")
		)
		(fp_line
			(start 0.7874 -0.4064)
			(end 0.7874 0.4064)
			(stroke
				(width 0.1524)
				(type default)
			)
			(layer "F.SilkS")
		)
		(fp_line
			(start -0.7874 0.4064)
			(end -0.7874 -0.4064)
			(stroke
				(width 0.1524)
				(type default)
			)
			(layer "F.SilkS")
		)
		(fp_line
			(start -0.7874 -0.4064)
			(end 0.7874 -0.4064)
			(stroke
				(width 0.1524)
				(type default)
			)
			(layer "F.SilkS")
		)
		(fp_line
			(start 0.67945 0.3048)
			(end 0.120396 0.3048)
			(stroke
				(width 0.1)
				(type default)
			)
			(layer "F.Fab")
		)
		(fp_line
			(start 0.67945 -0.3048)
			(end 0.67945 0.3048)
			(stroke
				(width 0.1)
				(type default)
			)
			(layer "F.Fab")
		)
		(fp_line
			(start 0.12065 -0.2794)
			(end 0.12065 -0.3048)
			(stroke
				(width 0.1)
				(type default)
			)
			(layer "F.Fab")
		)
		(fp_line
			(start 0.12065 -0.3048)
			(end 0.67945 -0.3048)
			(stroke
				(width 0.1)
				(type default)
			)
			(layer "F.Fab")
		)
		(fp_line
			(start 0.120396 0.3048)
			(end 0.120396 0.2794)
			(stroke
				(width 0.1)
				(type default)
			)
			(layer "F.Fab")
		)
		(fp_line
			(start 0.120396 0.2794)
			(end -0.12065 0.2794)
			(stroke
				(width 0.1)
				(type default)
			)
			(layer "F.Fab")
		)
		(fp_line
			(start -0.12065 0.3048)
			(end -0.67945 0.3048)
			(stroke
				(width 0.1)
				(type default)
			)
			(layer "F.Fab")
		)
		(fp_line
			(start -0.12065 0.2794)
			(end -0.12065 0.3048)
			(stroke
				(width 0.1)
				(type default)
			)
			(layer "F.Fab")
		)
		(fp_line
			(start -0.12065 -0.2794)
			(end 0.12065 -0.2794)
			(stroke
				(width 0.1)
				(type default)
			)
			(layer "F.Fab")
		)
		(fp_line
			(start -0.12065 -0.305054)
			(end -0.12065 -0.2794)
			(stroke
				(width 0.1)
				(type default)
			)
			(layer "F.Fab")
		)
		(fp_line
			(start -0.67945 0.3048)
			(end -0.67945 -0.305054)
			(stroke
				(width 0.1)
				(type default)
			)
			(layer "F.Fab")
		)
		(fp_line
			(start -0.67945 -0.305054)
			(end -0.12065 -0.305054)
			(stroke
				(width 0.1)
				(type default)
			)
			(layer "F.Fab")
		)
		(pad "1" smd circle
			(at -0.40005 0 180)
			(size 0 0)
			(layers "F.Cu" "F.Mask" "F.Paste")
			(net "P3V3_AUX")
		)
		(pad "2" smd circle
			(at 0.40005 0 180)
			(size 0 0)
			(layers "F.Cu" "F.Mask" "F.Paste")
			(net "HP_LVC3_OCP_V3_2_PRSNT2_N")
		)
	)
	(footprint ""
		(layer "F.Cu")
		(at 195.00088 -112.613948 -90)
		(property "Reference" "OSC2"
			(at 2.15773 2.276602 0)
			(unlocked yes)
			(layer "F.SilkS")
			(effects
				(font
					(size 0.7874 0.5842)
					(thickness 0.1524)
				)
				(justify left)
			)
		)
		(property "Value" ""
			(at 0 0 270)
			(layer "F.Fab")
			(effects
				(font
					(size 1.27 1.27)
				)
			)
		)
		(duplicate_pad_numbers_are_jumpers no)
		(fp_line
			(start -1.299972 1.599946)
			(end -1.299972 -1.599946)
			(stroke
				(width 0.1524)
				(type default)
			)
			(layer "F.SilkS")
		)
		(fp_line
			(start 1.299972 1.599946)
			(end -1.299972 1.599946)
			(stroke
				(width 0.1524)
				(type default)
			)
			(layer "F.SilkS")
		)
		(fp_line
			(start -1.299972 -1.599946)
			(end 1.299972 -1.599946)
			(stroke
				(width 0.1524)
				(type default)
			)
			(layer "F.SilkS")
		)
		(fp_line
			(start 1.299972 -1.599946)
			(end 1.299972 1.599946)
			(stroke
				(width 0.1524)
				(type default)
			)
			(layer "F.SilkS")
		)
		(fp_poly
			(pts
				(xy -2.4892 -1.26492) (xy -1.4732 -0.75692) (xy -2.4892 -0.24892)
			)
			(stroke
				(width 0)
				(type default)
			)
			(fill yes)
			(layer "F.SilkS")
		)
		(fp_line
			(start -1.050036 1.299972)
			(end -1.050036 -1.299972)
			(stroke
				(width 0.1)
				(type default)
			)
			(layer "F.Fab")
		)
		(fp_line
			(start 1.050036 1.299972)
			(end -1.050036 1.299972)
			(stroke
				(width 0.1)
				(type default)
			)
			(layer "F.Fab")
		)
		(fp_line
			(start -1.050036 -1.299972)
			(end 1.050036 -1.299972)
			(stroke
				(width 0.1)
				(type default)
			)
			(layer "F.Fab")
		)
		(fp_line
			(start 1.050036 -1.299972)
			(end 1.050036 1.299972)
			(stroke
				(width 0.1)
				(type default)
			)
			(layer "F.Fab")
		)
		(fp_poly
			(pts
				(xy -2.4892 -0.24892) (xy -2.4892 -1.26492) (xy -1.4732 -0.75692)
			)
			(stroke
				(width 0)
				(type default)
			)
			(fill yes)
			(layer "F.Fab")
		)
		(pad "1" smd rect
			(at -0.649986 -0.849884 270)
			(size 1.016 1.2192)
			(layers "F.Cu" "F.Mask" "F.Paste")
			(net "PU_CLK25M_OSC_FPGA_EN")
		)
		(pad "2" smd rect
			(at -0.649986 0.849884 270)
			(size 1.016 1.2192)
			(layers "F.Cu" "F.Mask" "F.Paste")
			(net "GND")
		)
		(pad "3" smd rect
			(at 0.649986 0.849884 270)
			(size 1.016 1.2192)
			(layers "F.Cu" "F.Mask" "F.Paste")
			(net "CLK_25M_OSC_FPGA_R")
		)
		(pad "4" smd rect
			(at 0.649986 -0.849884 270)
			(size 1.016 1.2192)
			(layers "F.Cu" "F.Mask" "F.Paste")
			(net "P3V3_AUX")
		)
	)
	(footprint ""
		(layer "F.Cu")
		(at 442.76518 -103.3272 90)
		(property "Reference" "R4749"
			(at 0 0 90)
			(layer "F.SilkS")
			(hide yes)
			(effects
				(font
					(size 1.27 1.27)
				)
			)
		)
		(property "Value" ""
			(at 0 0 90)
			(layer "F.Fab")
			(effects
				(font
					(size 1.27 1.27)
				)
			)
		)
		(duplicate_pad_numbers_are_jumpers no)
		(fp_line
			(start 0.7874 -0.4064)
			(end 0.7874 0.4064)
			(stroke
				(width 0.1524)
				(type default)
			)
			(layer "F.SilkS")
		)
		(fp_line
			(start -0.7874 -0.4064)
			(end 0.7874 -0.4064)
			(stroke
				(width 0.1524)
				(type default)
			)
			(layer "F.SilkS")
		)
		(fp_line
			(start 0.7874 0.4064)
			(end -0.7874 0.4064)
			(stroke
				(width 0.1524)
				(type default)
			)
			(layer "F.SilkS")
		)
		(fp_line
			(start -0.7874 0.4064)
			(end -0.7874 -0.4064)
			(stroke
				(width 0.1524)
				(type default)
			)
			(layer "F.SilkS")
		)
		(fp_line
			(start -0.12065 -0.305054)
			(end -0.12065 -0.2794)
			(stroke
				(width 0.1)
				(type default)
			)
			(layer "F.Fab")
		)
		(fp_line
			(start -0.67945 -0.305054)
			(end -0.12065 -0.305054)
			(stroke
				(width 0.1)
				(type default)
			)
			(layer "F.Fab")
		)
		(fp_line
			(start 0.67945 -0.3048)
			(end 0.67945 0.3048)
			(stroke
				(width 0.1)
				(type default)
			)
			(layer "F.Fab")
		)
		(fp_line
			(start 0.12065 -0.3048)
			(end 0.67945 -0.3048)
			(stroke
				(width 0.1)
				(type default)
			)
			(layer "F.Fab")
		)
		(fp_line
			(start 0.12065 -0.2794)
			(end 0.12065 -0.3048)
			(stroke
				(width 0.1)
				(type default)
			)
			(layer "F.Fab")
		)
		(fp_line
			(start -0.12065 -0.2794)
			(end 0.12065 -0.2794)
			(stroke
				(width 0.1)
				(type default)
			)
			(layer "F.Fab")
		)
		(fp_line
			(start 0.120396 0.2794)
			(end -0.12065 0.2794)
			(stroke
				(width 0.1)
				(type default)
			)
			(layer "F.Fab")
		)
		(fp_line
			(start -0.12065 0.2794)
			(end -0.12065 0.3048)
			(stroke
				(width 0.1)
				(type default)
			)
			(layer "F.Fab")
		)
		(fp_line
			(start 0.67945 0.3048)
			(end 0.120396 0.3048)
			(stroke
				(width 0.1)
				(type default)
			)
			(layer "F.Fab")
		)
		(fp_line
			(start 0.120396 0.3048)
			(end 0.120396 0.2794)
			(stroke
				(width 0.1)
				(type default)
			)
			(layer "F.Fab")
		)
		(fp_line
			(start -0.12065 0.3048)
			(end -0.67945 0.3048)
			(stroke
				(width 0.1)
				(type default)
			)
			(layer "F.Fab")
		)
		(fp_line
			(start -0.67945 0.3048)
			(end -0.67945 -0.305054)
			(stroke
				(width 0.1)
				(type default)
			)
			(layer "F.Fab")
		)
		(pad "1" smd circle
			(at -0.40005 0 90)
			(size 0 0)
			(layers "F.Cu" "F.Mask" "F.Paste")
			(net "OCP_SFF_AUX_PWR_PLD_EN_R")
		)
		(pad "2" smd circle
			(at 0.40005 0 90)
			(size 0 0)
			(layers "F.Cu" "F.Mask" "F.Paste")
			(net "OCP_SFF_AUX_PWR_EN_R2")
		)
	)
	(footprint ""
		(layer "F.Cu")
		(at 95.123 -417.683188 -90)
		(property "Reference" "R4545"
			(at 0 0 270)
			(layer "F.SilkS")
			(hide yes)
			(effects
				(font
					(size 1.27 1.27)
				)
			)
		)
		(property "Value" ""
			(at 0 0 270)
			(layer "F.Fab")
			(effects
				(font
					(size 1.27 1.27)
				)
			)
		)
		(duplicate_pad_numbers_are_jumpers no)
		(fp_line
			(start -0.7874 0.4064)
			(end -0.7874 -0.4064)
			(stroke
				(width 0.1524)
				(type default)
			)
			(layer "F.SilkS")
		)
		(fp_line
			(start 0.7874 0.4064)
			(end -0.7874 0.4064)
			(stroke
				(width 0.1524)
				(type default)
			)
			(layer "F.SilkS")
		)
		(fp_line
			(start -0.7874 -0.4064)
			(end 0.7874 -0.4064)
			(stroke
				(width 0.1524)
				(type default)
			)
			(layer "F.SilkS")
		)
		(fp_line
			(start 0.7874 -0.4064)
			(end 0.7874 0.4064)
			(stroke
				(width 0.1524)
				(type default)
			)
			(layer "F.SilkS")
		)
		(fp_line
			(start -0.67945 0.3048)
			(end -0.67945 -0.305054)
			(stroke
				(width 0.1)
				(type default)
			)
			(layer "F.Fab")
		)
		(fp_line
			(start -0.12065 0.3048)
			(end -0.67945 0.3048)
			(stroke
				(width 0.1)
				(type default)
			)
			(layer "F.Fab")
		)
		(fp_line
			(start 0.120396 0.3048)
			(end 0.120396 0.2794)
			(stroke
				(width 0.1)
				(type default)
			)
			(layer "F.Fab")
		)
		(fp_line
			(start 0.67945 0.3048)
			(end 0.120396 0.3048)
			(stroke
				(width 0.1)
				(type default)
			)
			(layer "F.Fab")
		)
		(fp_line
			(start -0.12065 0.2794)
			(end -0.12065 0.3048)
			(stroke
				(width 0.1)
				(type default)
			)
			(layer "F.Fab")
		)
		(fp_line
			(start 0.120396 0.2794)
			(end -0.12065 0.2794)
			(stroke
				(width 0.1)
				(type default)
			)
			(layer "F.Fab")
		)
		(fp_line
			(start -0.12065 -0.2794)
			(end 0.12065 -0.2794)
			(stroke
				(width 0.1)
				(type default)
			)
			(layer "F.Fab")
		)
		(fp_line
			(start 0.12065 -0.2794)
			(end 0.12065 -0.3048)
			(stroke
				(width 0.1)
				(type default)
			)
			(layer "F.Fab")
		)
		(fp_line
			(start 0.12065 -0.3048)
			(end 0.67945 -0.3048)
			(stroke
				(width 0.1)
				(type default)
			)
			(layer "F.Fab")
		)
		(fp_line
			(start 0.67945 -0.3048)
			(end 0.67945 0.3048)
			(stroke
				(width 0.1)
				(type default)
			)
			(layer "F.Fab")
		)
		(fp_line
			(start -0.67945 -0.305054)
			(end -0.12065 -0.305054)
			(stroke
				(width 0.1)
				(type default)
			)
			(layer "F.Fab")
		)
		(fp_line
			(start -0.12065 -0.305054)
			(end -0.12065 -0.2794)
			(stroke
				(width 0.1)
				(type default)
			)
			(layer "F.Fab")
		)
		(pad "1" smd circle
			(at -0.40005 0 270)
			(size 0 0)
			(layers "F.Cu" "F.Mask" "F.Paste")
			(net "P3V3_AUX")
		)
		(pad "2" smd circle
			(at 0.40005 0 270)
			(size 0 0)
			(layers "F.Cu" "F.Mask" "F.Paste")
			(net "HGX_DETECT")
		)
	)
	(footprint ""
		(layer "F.Cu")
		(at 362.13034 -410.700728)
		(property "Reference" "R4550"
			(at 0 0 0)
			(layer "F.SilkS")
			(hide yes)
			(effects
				(font
					(size 1.27 1.27)
				)
			)
		)
		(property "Value" ""
			(at 0 0 0)
			(layer "F.Fab")
			(effects
				(font
					(size 1.27 1.27)
				)
			)
		)
		(duplicate_pad_numbers_are_jumpers no)
		(fp_line
			(start -0.7874 -0.4064)
			(end 0.7874 -0.4064)
			(stroke
				(width 0.1524)
				(type default)
			)
			(layer "F.SilkS")
		)
		(fp_line
			(start -0.7874 0.4064)
			(end -0.7874 -0.4064)
			(stroke
				(width 0.1524)
				(type default)
			)
			(layer "F.SilkS")
		)
		(fp_line
			(start 0.7874 -0.4064)
			(end 0.7874 0.4064)
			(stroke
				(width 0.1524)
				(type default)
			)
			(layer "F.SilkS")
		)
		(fp_line
			(start 0.7874 0.4064)
			(end -0.7874 0.4064)
			(stroke
				(width 0.1524)
				(type default)
			)
			(layer "F.SilkS")
		)
		(fp_line
			(start -0.67945 -0.305054)
			(end -0.12065 -0.305054)
			(stroke
				(width 0.1)
				(type default)
			)
			(layer "F.Fab")
		)
		(fp_line
			(start -0.67945 0.3048)
			(end -0.67945 -0.305054)
			(stroke
				(width 0.1)
				(type default)
			)
			(layer "F.Fab")
		)
		(fp_line
			(start -0.12065 -0.305054)
			(end -0.12065 -0.2794)
			(stroke
				(width 0.1)
				(type default)
			)
			(layer "F.Fab")
		)
		(fp_line
			(start -0.12065 -0.2794)
			(end 0.12065 -0.2794)
			(stroke
				(width 0.1)
				(type default)
			)
			(layer "F.Fab")
		)
		(fp_line
			(start -0.12065 0.2794)
			(end -0.12065 0.3048)
			(stroke
				(width 0.1)
				(type default)
			)
			(layer "F.Fab")
		)
		(fp_line
			(start -0.12065 0.3048)
			(end -0.67945 0.3048)
			(stroke
				(width 0.1)
				(type default)
			)
			(layer "F.Fab")
		)
		(fp_line
			(start 0.120396 0.2794)
			(end -0.12065 0.2794)
			(stroke
				(width 0.1)
				(type default)
			)
			(layer "F.Fab")
		)
		(fp_line
			(start 0.120396 0.3048)
			(end 0.120396 0.2794)
			(stroke
				(width 0.1)
				(type default)
			)
			(layer "F.Fab")
		)
		(fp_line
			(start 0.12065 -0.3048)
			(end 0.67945 -0.3048)
			(stroke
				(width 0.1)
				(type default)
			)
			(layer "F.Fab")
		)
		(fp_line
			(start 0.12065 -0.2794)
			(end 0.12065 -0.3048)
			(stroke
				(width 0.1)
				(type default)
			)
			(layer "F.Fab")
		)
		(fp_line
			(start 0.67945 -0.3048)
			(end 0.67945 0.3048)
			(stroke
				(width 0.1)
				(type default)
			)
			(layer "F.Fab")
		)
		(fp_line
			(start 0.67945 0.3048)
			(end 0.120396 0.3048)
			(stroke
				(width 0.1)
				(type default)
			)
			(layer "F.Fab")
		)
		(pad "1" smd circle
			(at -0.40005 0)
			(size 0 0)
			(layers "F.Cu" "F.Mask" "F.Paste")
			(net "SWB_HSC_EN_BUF_R")
		)
		(pad "2" smd circle
			(at 0.40005 0)
			(size 0 0)
			(layers "F.Cu" "F.Mask" "F.Paste")
			(net "SWB_HSC_EN_BUF")
		)
	)
	(footprint ""
		(layer "F.Cu")
		(at 36.930584 -109.571282)
		(property "Reference" "C2049"
			(at 0 0 0)
			(layer "F.SilkS")
			(hide yes)
			(effects
				(font
					(size 1.27 1.27)
				)
			)
		)
		(property "Value" ""
			(at 0 0 0)
			(layer "F.Fab")
			(effects
				(font
					(size 1.27 1.27)
				)
			)
		)
		(duplicate_pad_numbers_are_jumpers no)
		(fp_line
			(start -0.7874 -0.4064)
			(end 0.7874 -0.4064)
			(stroke
				(width 0.1524)
				(type default)
			)
			(layer "F.SilkS")
		)
		(fp_line
			(start -0.7874 0.4064)
			(end -0.7874 -0.4064)
			(stroke
				(width 0.1524)
				(type default)
			)
			(layer "F.SilkS")
		)
		(fp_line
			(start 0.7874 -0.4064)
			(end 0.7874 0.4064)
			(stroke
				(width 0.1524)
				(type default)
			)
			(layer "F.SilkS")
		)
		(fp_line
			(start 0.7874 0.4064)
			(end -0.7874 0.4064)
			(stroke
				(width 0.1524)
				(type default)
			)
			(layer "F.SilkS")
		)
		(fp_line
			(start -0.67945 -0.305054)
			(end -0.12065 -0.305054)
			(stroke
				(width 0.1)
				(type default)
			)
			(layer "F.Fab")
		)
		(fp_line
			(start -0.67945 0.3048)
			(end -0.67945 -0.305054)
			(stroke
				(width 0.1)
				(type default)
			)
			(layer "F.Fab")
		)
		(fp_line
			(start -0.12065 -0.305054)
			(end -0.12065 -0.2794)
			(stroke
				(width 0.1)
				(type default)
			)
			(layer "F.Fab")
		)
		(fp_line
			(start -0.12065 -0.2794)
			(end 0.12065 -0.2794)
			(stroke
				(width 0.1)
				(type default)
			)
			(layer "F.Fab")
		)
		(fp_line
			(start -0.12065 0.2794)
			(end -0.12065 0.3048)
			(stroke
				(width 0.1)
				(type default)
			)
			(layer "F.Fab")
		)
		(fp_line
			(start -0.12065 0.3048)
			(end -0.67945 0.3048)
			(stroke
				(width 0.1)
				(type default)
			)
			(layer "F.Fab")
		)
		(fp_line
			(start 0.120396 0.2794)
			(end -0.12065 0.2794)
			(stroke
				(width 0.1)
				(type default)
			)
			(layer "F.Fab")
		)
		(fp_line
			(start 0.120396 0.3048)
			(end 0.120396 0.2794)
			(stroke
				(width 0.1)
				(type default)
			)
			(layer "F.Fab")
		)
		(fp_line
			(start 0.12065 -0.3048)
			(end 0.67945 -0.3048)
			(stroke
				(width 0.1)
				(type default)
			)
			(layer "F.Fab")
		)
		(fp_line
			(start 0.12065 -0.2794)
			(end 0.12065 -0.3048)
			(stroke
				(width 0.1)
				(type default)
			)
			(layer "F.Fab")
		)
		(fp_line
			(start 0.67945 -0.3048)
			(end 0.67945 0.3048)
			(stroke
				(width 0.1)
				(type default)
			)
			(layer "F.Fab")
		)
		(fp_line
			(start 0.67945 0.3048)
			(end 0.120396 0.3048)
			(stroke
				(width 0.1)
				(type default)
			)
			(layer "F.Fab")
		)
		(pad "1" smd circle
			(at -0.40005 0)
			(size 0 0)
			(layers "F.Cu" "F.Mask" "F.Paste")
			(net "P5V_ADC_TIC")
		)
		(pad "2" smd circle
			(at 0.40005 0)
			(size 0 0)
			(layers "F.Cu" "F.Mask" "F.Paste")
			(net "GND")
		)
	)
)
